(kicad_pcb
	(version 20260206)
	(generator "pcbnew")
	(generator_version "10.0")
	(general
		(thickness 1.6)
		(legacy_teardrops no)
	)
	(paper "A4")
	(title_block
		(title "04192023_DAF0TMB3IC0_F0TG_MB_C_brd_V02_OCP.brd")
		(comment 1 "Grand Teton / footprints 7426-7433 of 8354")
	)
	(layers
		(0 "F.Cu" signal "TOP")
		(4 "In1.Cu" signal "GND")
		(6 "In2.Cu" signal "IN1")
		(8 "In3.Cu" signal "GND1")
		(10 "In4.Cu" signal "IN2")
		(12 "In5.Cu" signal "GND2")
		(14 "In6.Cu" signal "IN3")
		(16 "In7.Cu" signal "GND3")
		(18 "In8.Cu" signal "VCC")
		(20 "In9.Cu" signal "VCC1")
		(22 "In10.Cu" signal "GND4")
		(24 "In11.Cu" signal "IN4")
		(26 "In12.Cu" signal "GND5")
		(28 "In13.Cu" signal "IN5")
		(30 "In14.Cu" signal "GND6")
		(32 "In15.Cu" signal "IN6")
		(34 "In16.Cu" signal "GND7")
		(2 "B.Cu" signal "BOTTOM")
		(9 "F.Adhes" user "F.Adhesive")
		(11 "B.Adhes" user "B.Adhesive")
		(13 "F.Paste" user "Package Geometry/Pastemask Top")
		(15 "B.Paste" user "Package Geometry/Pastemask Bottom")
		(5 "F.SilkS" user "Ref Des/Silkscreen Top")
		(7 "B.SilkS" user "Ref Des/Silkscreen Bottom")
		(1 "F.Mask" user "Board Geometry/Soldermask Top")
		(3 "B.Mask" user "Board Geometry/Soldermask Bottom")
		(17 "Dwgs.User" user "User.Drawings")
		(19 "Cmts.User" user "User.Comments")
		(21 "Eco1.User" user "User.Eco1")
		(23 "Eco2.User" user "User.Eco2")
		(25 "Edge.Cuts" user "Board Geometry/Outline")
		(27 "Margin" user)
		(31 "F.CrtYd" user "Package Geometry/Place Bound Top")
		(29 "B.CrtYd" user "Package Geometry/Place Bound Bottom")
		(35 "F.Fab" user "Ref Des/Assembly Top")
		(33 "B.Fab" user "Ref Des/Assembly Bottom")
	)
	(footprint ""
		(layer "B.Cu")
		(at 62.978538 -386.766562 90)
		(property "Reference" "C222"
			(at 0 0 90)
			(layer "B.SilkS")
			(hide yes)
			(effects
				(font
					(size 1.27 1.27)
				)
				(justify mirror)
			)
		)
		(property "Value" ""
			(at 0 0 90)
			(layer "B.Fab")
			(effects
				(font
					(size 1.27 1.27)
				)
				(justify mirror)
			)
		)
		(duplicate_pad_numbers_are_jumpers no)
		(fp_line
			(start 0.299974 -0.150114)
			(end -0.299974 -0.150114)
			(stroke
				(width 0.1)
				(type default)
			)
			(layer "B.Fab")
		)
		(fp_line
			(start -0.299974 -0.150114)
			(end -0.299974 0.150114)
			(stroke
				(width 0.1)
				(type default)
			)
			(layer "B.Fab")
		)
		(fp_line
			(start 0.299974 0.150114)
			(end 0.299974 -0.150114)
			(stroke
				(width 0.1)
				(type default)
			)
			(layer "B.Fab")
		)
		(fp_line
			(start -0.299974 0.150114)
			(end 0.299974 0.150114)
			(stroke
				(width 0.1)
				(type default)
			)
			(layer "B.Fab")
		)
		(pad "1" smd rect
			(at 0.2667 0 270)
			(size 0.3048 0.381)
			(layers "B.Cu" "B.Mask" "B.Paste")
			(net "P0V9_CPU1_RT0_2A")
		)
		(pad "2" smd rect
			(at -0.2667 0 270)
			(size 0.3048 0.381)
			(layers "B.Cu" "B.Mask" "B.Paste")
			(net "GND")
		)
	)
	(footprint ""
		(layer "B.Cu")
		(at 61.52388 -8.981948 90)
		(property "Reference" "C1836"
			(at 0 0 90)
			(layer "B.SilkS")
			(hide yes)
			(effects
				(font
					(size 1.27 1.27)
				)
				(justify mirror)
			)
		)
		(property "Value" ""
			(at 0 0 90)
			(layer "B.Fab")
			(effects
				(font
					(size 1.27 1.27)
				)
				(justify mirror)
			)
		)
		(duplicate_pad_numbers_are_jumpers no)
		(fp_line
			(start 0.7874 -0.4064)
			(end -0.7874 -0.4064)
			(stroke
				(width 0.1524)
				(type default)
			)
			(layer "B.SilkS")
		)
		(fp_line
			(start -0.7874 -0.4064)
			(end -0.7874 0.4064)
			(stroke
				(width 0.1524)
				(type default)
			)
			(layer "B.SilkS")
		)
		(fp_line
			(start 0.7874 0.4064)
			(end 0.7874 -0.4064)
			(stroke
				(width 0.1524)
				(type default)
			)
			(layer "B.SilkS")
		)
		(fp_line
			(start -0.7874 0.4064)
			(end 0.7874 0.4064)
			(stroke
				(width 0.1524)
				(type default)
			)
			(layer "B.SilkS")
		)
		(fp_line
			(start 0.67945 -0.305054)
			(end 0.12065 -0.305054)
			(stroke
				(width 0.1)
				(type default)
			)
			(layer "B.Fab")
		)
		(fp_line
			(start 0.12065 -0.305054)
			(end 0.12065 -0.2794)
			(stroke
				(width 0.1)
				(type default)
			)
			(layer "B.Fab")
		)
		(fp_line
			(start -0.12065 -0.3048)
			(end -0.67945 -0.3048)
			(stroke
				(width 0.1)
				(type default)
			)
			(layer "B.Fab")
		)
		(fp_line
			(start -0.67945 -0.3048)
			(end -0.67945 0.3048)
			(stroke
				(width 0.1)
				(type default)
			)
			(layer "B.Fab")
		)
		(fp_line
			(start 0.12065 -0.2794)
			(end -0.12065 -0.2794)
			(stroke
				(width 0.1)
				(type default)
			)
			(layer "B.Fab")
		)
		(fp_line
			(start -0.12065 -0.2794)
			(end -0.12065 -0.3048)
			(stroke
				(width 0.1)
				(type default)
			)
			(layer "B.Fab")
		)
		(fp_line
			(start 0.12065 0.2794)
			(end 0.12065 0.3048)
			(stroke
				(width 0.1)
				(type default)
			)
			(layer "B.Fab")
		)
		(fp_line
			(start -0.120396 0.2794)
			(end 0.12065 0.2794)
			(stroke
				(width 0.1)
				(type default)
			)
			(layer "B.Fab")
		)
		(fp_line
			(start 0.67945 0.3048)
			(end 0.67945 -0.305054)
			(stroke
				(width 0.1)
				(type default)
			)
			(layer "B.Fab")
		)
		(fp_line
			(start 0.12065 0.3048)
			(end 0.67945 0.3048)
			(stroke
				(width 0.1)
				(type default)
			)
			(layer "B.Fab")
		)
		(fp_line
			(start -0.120396 0.3048)
			(end -0.120396 0.2794)
			(stroke
				(width 0.1)
				(type default)
			)
			(layer "B.Fab")
		)
		(fp_line
			(start -0.67945 0.3048)
			(end -0.120396 0.3048)
			(stroke
				(width 0.1)
				(type default)
			)
			(layer "B.Fab")
		)
		(pad "1" smd circle
			(at 0.40005 0 270)
			(size 0 0)
			(layers "B.Cu" "B.Mask" "B.Paste")
			(net "P3V3_OCP_V3_2")
		)
		(pad "2" smd circle
			(at -0.40005 0 270)
			(size 0 0)
			(layers "B.Cu" "B.Mask" "B.Paste")
			(net "GND")
		)
	)
	(footprint ""
		(layer "B.Cu")
		(at 199.96912 -331.027786 -90)
		(property "Reference" "PC129"
			(at 0 0 90)
			(layer "B.SilkS")
			(hide yes)
			(effects
				(font
					(size 1.27 1.27)
				)
				(justify mirror)
			)
		)
		(property "Value" ""
			(at 0 0 90)
			(layer "B.Fab")
			(effects
				(font
					(size 1.27 1.27)
				)
				(justify mirror)
			)
		)
		(duplicate_pad_numbers_are_jumpers no)
		(fp_line
			(start -1.524 0.762)
			(end 1.524 0.762)
			(stroke
				(width 0.1524)
				(type default)
			)
			(layer "B.SilkS")
		)
		(fp_line
			(start 1.524 0.762)
			(end 1.524 -0.762)
			(stroke
				(width 0.1524)
				(type default)
			)
			(layer "B.SilkS")
		)
		(fp_line
			(start -1.524 -0.762)
			(end -1.524 0.762)
			(stroke
				(width 0.1524)
				(type default)
			)
			(layer "B.SilkS")
		)
		(fp_line
			(start 1.524 -0.762)
			(end -1.524 -0.762)
			(stroke
				(width 0.1524)
				(type default)
			)
			(layer "B.SilkS")
		)
		(fp_line
			(start -1.1049 0.724916)
			(end -1.1049 -0.724916)
			(stroke
				(width 0.1)
				(type default)
			)
			(layer "B.Fab")
		)
		(fp_line
			(start 1.1049 0.724916)
			(end -1.1049 0.724916)
			(stroke
				(width 0.1)
				(type default)
			)
			(layer "B.Fab")
		)
		(fp_line
			(start -1.1049 -0.724916)
			(end 1.1049 -0.724916)
			(stroke
				(width 0.1)
				(type default)
			)
			(layer "B.Fab")
		)
		(fp_line
			(start 1.1049 -0.724916)
			(end 1.1049 0.724916)
			(stroke
				(width 0.1)
				(type default)
			)
			(layer "B.Fab")
		)
		(pad "1" smd rect
			(at 0.889 0 270)
			(size 1.016 1.27)
			(layers "B.Cu" "B.Mask" "B.Paste")
			(net "PVDD_33_S5")
		)
		(pad "2" smd rect
			(at -0.889 0 270)
			(size 1.016 1.27)
			(layers "B.Cu" "B.Mask" "B.Paste")
			(net "GND")
		)
	)
	(footprint ""
		(layer "B.Cu")
		(at 359.740454 -251.40031 180)
		(property "Reference" "C2595"
			(at 0 0 0)
			(layer "B.SilkS")
			(hide yes)
			(effects
				(font
					(size 1.27 1.27)
				)
				(justify mirror)
			)
		)
		(property "Value" ""
			(at 0 0 0)
			(layer "B.Fab")
			(effects
				(font
					(size 1.27 1.27)
				)
				(justify mirror)
			)
		)
		(duplicate_pad_numbers_are_jumpers no)
		(fp_line
			(start 0.7874 0.4064)
			(end 0.7874 -0.4064)
			(stroke
				(width 0.1524)
				(type default)
			)
			(layer "B.SilkS")
		)
		(fp_line
			(start 0.7874 -0.4064)
			(end -0.7874 -0.4064)
			(stroke
				(width 0.1524)
				(type default)
			)
			(layer "B.SilkS")
		)
		(fp_line
			(start -0.7874 0.4064)
			(end 0.7874 0.4064)
			(stroke
				(width 0.1524)
				(type default)
			)
			(layer "B.SilkS")
		)
		(fp_line
			(start -0.7874 -0.4064)
			(end -0.7874 0.4064)
			(stroke
				(width 0.1524)
				(type default)
			)
			(layer "B.SilkS")
		)
		(fp_line
			(start 0.67945 0.3048)
			(end 0.67945 -0.305054)
			(stroke
				(width 0.1)
				(type default)
			)
			(layer "B.Fab")
		)
		(fp_line
			(start 0.67945 -0.305054)
			(end 0.12065 -0.305054)
			(stroke
				(width 0.1)
				(type default)
			)
			(layer "B.Fab")
		)
		(fp_line
			(start 0.12065 0.3048)
			(end 0.67945 0.3048)
			(stroke
				(width 0.1)
				(type default)
			)
			(layer "B.Fab")
		)
		(fp_line
			(start 0.12065 0.2794)
			(end 0.12065 0.3048)
			(stroke
				(width 0.1)
				(type default)
			)
			(layer "B.Fab")
		)
		(fp_line
			(start 0.12065 -0.2794)
			(end -0.12065 -0.2794)
			(stroke
				(width 0.1)
				(type default)
			)
			(layer "B.Fab")
		)
		(fp_line
			(start 0.12065 -0.305054)
			(end 0.12065 -0.2794)
			(stroke
				(width 0.1)
				(type default)
			)
			(layer "B.Fab")
		)
		(fp_line
			(start -0.120396 0.3048)
			(end -0.120396 0.2794)
			(stroke
				(width 0.1)
				(type default)
			)
			(layer "B.Fab")
		)
		(fp_line
			(start -0.120396 0.2794)
			(end 0.12065 0.2794)
			(stroke
				(width 0.1)
				(type default)
			)
			(layer "B.Fab")
		)
		(fp_line
			(start -0.12065 -0.2794)
			(end -0.12065 -0.3048)
			(stroke
				(width 0.1)
				(type default)
			)
			(layer "B.Fab")
		)
		(fp_line
			(start -0.12065 -0.3048)
			(end -0.67945 -0.3048)
			(stroke
				(width 0.1)
				(type default)
			)
			(layer "B.Fab")
		)
		(fp_line
			(start -0.67945 0.3048)
			(end -0.120396 0.3048)
			(stroke
				(width 0.1)
				(type default)
			)
			(layer "B.Fab")
		)
		(fp_line
			(start -0.67945 -0.3048)
			(end -0.67945 0.3048)
			(stroke
				(width 0.1)
				(type default)
			)
			(layer "B.Fab")
		)
		(pad "1" smd circle
			(at 0.40005 0)
			(size 0 0)
			(layers "B.Cu" "B.Mask" "B.Paste")
			(net "PVDDCR_SOC_P0")
		)
		(pad "2" smd circle
			(at -0.40005 0)
			(size 0 0)
			(layers "B.Cu" "B.Mask" "B.Paste")
			(net "GND")
		)
	)
	(footprint ""
		(layer "B.Cu")
		(at 238.633 -340.741 180)
		(property "Reference" "R808"
			(at 0 0 0)
			(layer "B.SilkS")
			(hide yes)
			(effects
				(font
					(size 1.27 1.27)
				)
				(justify mirror)
			)
		)
		(property "Value" ""
			(at 0 0 0)
			(layer "B.Fab")
			(effects
				(font
					(size 1.27 1.27)
				)
				(justify mirror)
			)
		)
		(duplicate_pad_numbers_are_jumpers no)
		(fp_line
			(start 0.32512 0.175006)
			(end 0.32512 -0.175006)
			(stroke
				(width 0.1)
				(type default)
			)
			(layer "B.Fab")
		)
		(fp_line
			(start 0.32512 -0.175006)
			(end -0.32512 -0.175006)
			(stroke
				(width 0.1)
				(type default)
			)
			(layer "B.Fab")
		)
		(fp_line
			(start -0.32512 0.175006)
			(end 0.32512 0.175006)
			(stroke
				(width 0.1)
				(type default)
			)
			(layer "B.Fab")
		)
		(fp_line
			(start -0.32512 -0.175006)
			(end -0.32512 0.175006)
			(stroke
				(width 0.1)
				(type default)
			)
			(layer "B.Fab")
		)
		(pad "1" smd rect
			(at 0.2667 0)
			(size 0.3048 0.381)
			(layers "B.Cu" "B.Mask" "B.Paste")
			(net "SMB_RT_CPU1_P2_ROM_MUX_2D_SDA")
		)
		(pad "2" smd rect
			(at -0.2667 0 180)
			(size 0.3048 0.381)
			(layers "B.Cu" "B.Mask" "B.Paste")
			(net "SMB_RT_CPU1_P2_ROM_MUX_2D_R_SDA")
		)
	)
	(footprint ""
		(layer "B.Cu")
		(at 384.240278 -137.535158 90)
		(property "Reference" "PC471"
			(at 0 0 90)
			(layer "B.SilkS")
			(hide yes)
			(effects
				(font
					(size 1.27 1.27)
				)
				(justify mirror)
			)
		)
		(property "Value" ""
			(at 0 0 90)
			(layer "B.Fab")
			(effects
				(font
					(size 1.27 1.27)
				)
				(justify mirror)
			)
		)
		(duplicate_pad_numbers_are_jumpers no)
		(fp_line
			(start 0.7874 -0.4064)
			(end -0.7874 -0.4064)
			(stroke
				(width 0.1524)
				(type default)
			)
			(layer "B.SilkS")
		)
		(fp_line
			(start -0.7874 -0.4064)
			(end -0.7874 0.4064)
			(stroke
				(width 0.1524)
				(type default)
			)
			(layer "B.SilkS")
		)
		(fp_line
			(start 0.7874 0.4064)
			(end 0.7874 -0.4064)
			(stroke
				(width 0.1524)
				(type default)
			)
			(layer "B.SilkS")
		)
		(fp_line
			(start -0.7874 0.4064)
			(end 0.7874 0.4064)
			(stroke
				(width 0.1524)
				(type default)
			)
			(layer "B.SilkS")
		)
		(fp_line
			(start 0.67945 -0.305054)
			(end 0.12065 -0.305054)
			(stroke
				(width 0.1)
				(type default)
			)
			(layer "B.Fab")
		)
		(fp_line
			(start 0.12065 -0.305054)
			(end 0.12065 -0.2794)
			(stroke
				(width 0.1)
				(type default)
			)
			(layer "B.Fab")
		)
		(fp_line
			(start -0.12065 -0.3048)
			(end -0.67945 -0.3048)
			(stroke
				(width 0.1)
				(type default)
			)
			(layer "B.Fab")
		)
		(fp_line
			(start -0.67945 -0.3048)
			(end -0.67945 0.3048)
			(stroke
				(width 0.1)
				(type default)
			)
			(layer "B.Fab")
		)
		(fp_line
			(start 0.12065 -0.2794)
			(end -0.12065 -0.2794)
			(stroke
				(width 0.1)
				(type default)
			)
			(layer "B.Fab")
		)
		(fp_line
			(start -0.12065 -0.2794)
			(end -0.12065 -0.3048)
			(stroke
				(width 0.1)
				(type default)
			)
			(layer "B.Fab")
		)
		(fp_line
			(start 0.12065 0.2794)
			(end 0.12065 0.3048)
			(stroke
				(width 0.1)
				(type default)
			)
			(layer "B.Fab")
		)
		(fp_line
			(start -0.120396 0.2794)
			(end 0.12065 0.2794)
			(stroke
				(width 0.1)
				(type default)
			)
			(layer "B.Fab")
		)
		(fp_line
			(start 0.67945 0.3048)
			(end 0.67945 -0.305054)
			(stroke
				(width 0.1)
				(type default)
			)
			(layer "B.Fab")
		)
		(fp_line
			(start 0.12065 0.3048)
			(end 0.67945 0.3048)
			(stroke
				(width 0.1)
				(type default)
			)
			(layer "B.Fab")
		)
		(fp_line
			(start -0.120396 0.3048)
			(end -0.120396 0.2794)
			(stroke
				(width 0.1)
				(type default)
			)
			(layer "B.Fab")
		)
		(fp_line
			(start -0.67945 0.3048)
			(end -0.120396 0.3048)
			(stroke
				(width 0.1)
				(type default)
			)
			(layer "B.Fab")
		)
		(pad "1" smd circle
			(at 0.40005 0 270)
			(size 0 0)
			(layers "B.Cu" "B.Mask" "B.Paste")
			(net "PVDDCR_CPU0_P0_VCC")
		)
		(pad "2" smd circle
			(at -0.40005 0 270)
			(size 0 0)
			(layers "B.Cu" "B.Mask" "B.Paste")
			(net "GND")
		)
	)
	(footprint ""
		(layer "B.Cu")
		(at 93.142562 -336.088482 -90)
		(property "Reference" "PR271"
			(at 0 0 90)
			(layer "B.SilkS")
			(hide yes)
			(effects
				(font
					(size 1.27 1.27)
				)
				(justify mirror)
			)
		)
		(property "Value" ""
			(at 0 0 90)
			(layer "B.Fab")
			(effects
				(font
					(size 1.27 1.27)
				)
				(justify mirror)
			)
		)
		(duplicate_pad_numbers_are_jumpers no)
		(fp_line
			(start -0.7874 0.4064)
			(end 0.7874 0.4064)
			(stroke
				(width 0.1524)
				(type default)
			)
			(layer "B.SilkS")
		)
		(fp_line
			(start 0.7874 0.4064)
			(end 0.7874 -0.4064)
			(stroke
				(width 0.1524)
				(type default)
			)
			(layer "B.SilkS")
		)
		(fp_line
			(start -0.7874 -0.4064)
			(end -0.7874 0.4064)
			(stroke
				(width 0.1524)
				(type default)
			)
			(layer "B.SilkS")
		)
		(fp_line
			(start 0.7874 -0.4064)
			(end -0.7874 -0.4064)
			(stroke
				(width 0.1524)
				(type default)
			)
			(layer "B.SilkS")
		)
		(fp_line
			(start -0.67945 0.3048)
			(end -0.120396 0.3048)
			(stroke
				(width 0.1)
				(type default)
			)
			(layer "B.Fab")
		)
		(fp_line
			(start -0.120396 0.3048)
			(end -0.120396 0.2794)
			(stroke
				(width 0.1)
				(type default)
			)
			(layer "B.Fab")
		)
		(fp_line
			(start 0.12065 0.3048)
			(end 0.67945 0.3048)
			(stroke
				(width 0.1)
				(type default)
			)
			(layer "B.Fab")
		)
		(fp_line
			(start 0.67945 0.3048)
			(end 0.67945 -0.305054)
			(stroke
				(width 0.1)
				(type default)
			)
			(layer "B.Fab")
		)
		(fp_line
			(start -0.120396 0.2794)
			(end 0.12065 0.2794)
			(stroke
				(width 0.1)
				(type default)
			)
			(layer "B.Fab")
		)
		(fp_line
			(start 0.12065 0.2794)
			(end 0.12065 0.3048)
			(stroke
				(width 0.1)
				(type default)
			)
			(layer "B.Fab")
		)
		(fp_line
			(start -0.12065 -0.2794)
			(end -0.12065 -0.3048)
			(stroke
				(width 0.1)
				(type default)
			)
			(layer "B.Fab")
		)
		(fp_line
			(start 0.12065 -0.2794)
			(end -0.12065 -0.2794)
			(stroke
				(width 0.1)
				(type default)
			)
			(layer "B.Fab")
		)
		(fp_line
			(start -0.67945 -0.3048)
			(end -0.67945 0.3048)
			(stroke
				(width 0.1)
				(type default)
			)
			(layer "B.Fab")
		)
		(fp_line
			(start -0.12065 -0.3048)
			(end -0.67945 -0.3048)
			(stroke
				(width 0.1)
				(type default)
			)
			(layer "B.Fab")
		)
		(fp_line
			(start 0.12065 -0.305054)
			(end 0.12065 -0.2794)
			(stroke
				(width 0.1)
				(type default)
			)
			(layer "B.Fab")
		)
		(fp_line
			(start 0.67945 -0.305054)
			(end 0.12065 -0.305054)
			(stroke
				(width 0.1)
				(type default)
			)
			(layer "B.Fab")
		)
		(pad "1" smd circle
			(at 0.40005 0 90)
			(size 0 0)
			(layers "B.Cu" "B.Mask" "B.Paste")
			(net "PVDDCR_CPU1_P1_PVCC")
		)
		(pad "2" smd circle
			(at -0.40005 0 90)
			(size 0 0)
			(layers "B.Cu" "B.Mask" "B.Paste")
			(net "PVDDCR_CPU1_P1_VCC5")
		)
	)
	(footprint ""
		(layer "B.Cu")
		(at 275.217128 -339.860128 -90)
		(property "Reference" "PC160"
			(at 9.447276 -0.827786 270)
			(unlocked yes)
			(layer "B.SilkS")
			(effects
				(font
					(size 0.7874 0.5842)
					(thickness 0.1524)
				)
				(justify left mirror)
			)
		)
		(property "Value" ""
			(at 0 0 90)
			(layer "B.Fab")
			(effects
				(font
					(size 1.27 1.27)
				)
				(justify mirror)
			)
		)
		(duplicate_pad_numbers_are_jumpers no)
		(fp_line
			(start -4.533392 2.249932)
			(end 4.533392 2.249932)
			(stroke
				(width 0.1524)
				(type default)
			)
			(layer "B.SilkS")
		)
		(fp_line
			(start 4.533392 2.249932)
			(end 4.533392 -2.249932)
			(stroke
				(width 0.1524)
				(type default)
			)
			(layer "B.SilkS")
		)
		(fp_line
			(start -4.533392 -2.249932)
			(end -4.533392 2.249932)
			(stroke
				(width 0.1524)
				(type default)
			)
			(layer "B.SilkS")
		)
		(fp_line
			(start 4.533392 -2.249932)
			(end -4.533392 -2.249932)
			(stroke
				(width 0.1524)
				(type default)
			)
			(layer "B.SilkS")
		)
		(fp_rect
			(start 5.39242 2.326132)
			(end 4.533392 -2.326132)
			(stroke
				(width 0)
				(type default)
			)
			(fill yes)
			(layer "B.SilkS")
		)
		(fp_line
			(start -3.750056 2.249932)
			(end 3.750056 2.249932)
			(stroke
				(width 0.1)
				(type default)
			)
			(layer "B.Fab")
		)
		(fp_line
			(start 3.750056 2.249932)
			(end 3.750056 -2.249932)
			(stroke
				(width 0.1)
				(type default)
			)
			(layer "B.Fab")
		)
		(fp_line
			(start -3.750056 -2.249932)
			(end -3.750056 2.249932)
			(stroke
				(width 0.1)
				(type default)
			)
			(layer "B.Fab")
		)
		(fp_line
			(start 3.750056 -2.249932)
			(end -3.750056 -2.249932)
			(stroke
				(width 0.1)
				(type default)
			)
			(layer "B.Fab")
		)
		(fp_text user "+"
			(at 6.322314 0.786384 180)
			(unlocked yes)
			(layer "B.SilkS")
			(effects
				(font
					(size 1.905 1.4224)
					(thickness 0.1524)
				)
				(justify left mirror)
			)
		)
		(fp_text user "-"
			(at -4.8514 -0.14605 270)
			(unlocked yes)
			(layer "B.SilkS")
			(effects
				(font
					(size 1.905 1.4224)
					(thickness 0.1524)
				)
				(justify left mirror)
			)
		)
		(fp_text user "+"
			(at 6.322314 0.786384 180)
			(unlocked yes)
			(layer "B.Fab")
			(effects
				(font
					(size 1.905 1.4224)
					(thickness 0.1524)
				)
				(justify left mirror)
			)
		)
		(fp_text user "-"
			(at -4.8514 -0.14605 270)
			(unlocked yes)
			(layer "B.Fab")
			(effects
				(font
					(size 1.905 1.4224)
					(thickness 0.1524)
				)
				(justify left mirror)
			)
		)
		(pad "1" smd rect
			(at 3.199892 0 90)
			(size 2.413 2.8194)
			(layers "B.Cu" "B.Mask" "B.Paste")
			(net "PVDDIO_P0")
		)
		(pad "2" smd rect
			(at -3.199892 0 90)
			(size 2.413 2.8194)
			(layers "B.Cu" "B.Mask" "B.Paste")
			(net "GND")
		)
	)
)
